(kicad_pcb
	(version 20260206)
	(generator "pcbnew")
	(generator_version "10.0")
	(general
		(thickness 1.6)
		(legacy_teardrops no)
	)
	(paper "A4")
	(title_block
		(title "Bryce Canyon_F.DPB_16315-1-OCP.brd")
		(comment 1 "Bryce Canyon / footprints 861-867 of 2223")
	)
	(layers
		(0 "F.Cu" signal "TOP")
		(4 "In1.Cu" signal "L2GND")
		(6 "In2.Cu" signal "L3")
		(8 "In3.Cu" signal "L4GND")
		(10 "In4.Cu" signal "L5")
		(12 "In5.Cu" signal "L6VCC")
		(14 "In6.Cu" signal "L7VCC")
		(16 "In7.Cu" signal "L8")
		(18 "In8.Cu" signal "L9GND")
		(20 "In9.Cu" signal "L10")
		(22 "In10.Cu" signal "L11GND")
		(2 "B.Cu" signal "BOTTOM")
		(9 "F.Adhes" user "F.Adhesive")
		(11 "B.Adhes" user "B.Adhesive")
		(13 "F.Paste" user "Package Geometry/Pastemask Top")
		(15 "B.Paste" user "Package Geometry/Pastemask Bottom")
		(5 "F.SilkS" user "Ref Des/Silkscreen Top")
		(7 "B.SilkS" user "Ref Des/Silkscreen Bottom")
		(1 "F.Mask" user "Board Geometry/Soldermask Top")
		(3 "B.Mask" user "Board Geometry/Soldermask Bottom")
		(17 "Dwgs.User" user "User.Drawings")
		(19 "Cmts.User" user "User.Comments")
		(21 "Eco1.User" user "User.Eco1")
		(23 "Eco2.User" user "User.Eco2")
		(25 "Edge.Cuts" user "Board Geometry/Outline")
		(27 "Margin" user)
		(31 "F.CrtYd" user "Package Geometry/Place Bound Top")
		(29 "B.CrtYd" user "Package Geometry/Place Bound Bottom")
		(35 "F.Fab" user "Ref Des/Assembly Top")
		(33 "B.Fab" user "Ref Des/Assembly Bottom")
	)
	(footprint ""
		(layer "F.Cu")
		(at 146.249898 -176.000918 -90)
		(property "Reference" "C249"
			(at 0 0 270)
			(layer "F.SilkS")
			(hide yes)
			(effects
				(font
					(size 1.27 1.27)
				)
			)
		)
		(property "Value" "SC10U16V6KX-2GP"
			(at -0.0762 -5.1308 270)
			(unlocked yes)
			(layer "F.Fab")
			(hide yes)
			(effects
				(font
					(size 1.016 1.016)
					(thickness 0.1524)
				)
			)
		)
		(property "Device Type" "C1206H71"
			(at -0.127 -6.6548 270)
			(unlocked yes)
			(layer "F.Fab")
			(hide yes)
			(effects
				(font
					(size 1.016 1.016)
					(thickness 0.1524)
				)
			)
		)
		(duplicate_pad_numbers_are_jumpers no)
		(fp_line
			(start -1.016 2.2352)
			(end -1.016 0.8382)
			(stroke
				(width 0.1524)
				(type default)
			)
			(layer "F.SilkS")
		)
		(fp_line
			(start 1.016 2.2352)
			(end -1.016 2.2352)
			(stroke
				(width 0.1524)
				(type default)
			)
			(layer "F.SilkS")
		)
		(fp_line
			(start 1.016 0.8382)
			(end 1.016 2.2352)
			(stroke
				(width 0.1524)
				(type default)
			)
			(layer "F.SilkS")
		)
		(fp_line
			(start -1.016 -0.8382)
			(end -1.016 -2.2352)
			(stroke
				(width 0.1524)
				(type default)
			)
			(layer "F.SilkS")
		)
		(fp_line
			(start -1.016 -2.2352)
			(end 1.016 -2.2352)
			(stroke
				(width 0.1524)
				(type default)
			)
			(layer "F.SilkS")
		)
		(fp_line
			(start 1.016 -2.2352)
			(end 1.016 -0.8382)
			(stroke
				(width 0.1524)
				(type default)
			)
			(layer "F.SilkS")
		)
		(fp_rect
			(start -1.0922 2.3114)
			(end 1.0922 -2.3114)
			(stroke
				(width 0)
				(type default)
			)
			(fill no)
			(layer "F.CrtYd")
		)
		(fp_poly
			(pts
				(xy 1.0922 -2.3114) (xy 1.0922 2.3114) (xy -1.0922 2.3114) (xy -1.0922 -2.3114)
			)
			(stroke
				(width 0)
				(type default)
			)
			(fill no)
			(layer "F.Fab")
		)
		(pad "1" smd rect
			(at 0 -1.397 270)
			(size 1.651 1.27)
			(layers "F.Cu" "F.Mask" "F.Paste")
			(net "P5V_HDD16")
		)
		(pad "2" smd rect
			(at 0 1.397 270)
			(size 1.651 1.27)
			(layers "F.Cu" "F.Mask" "F.Paste")
			(net "GND")
		)
	)
	(footprint ""
		(layer "F.Cu")
		(at 15.223998 -162.157918 180)
		(property "Reference" "R422"
			(at 0 0 180)
			(layer "F.SilkS")
			(hide yes)
			(effects
				(font
					(size 1.27 1.27)
				)
			)
		)
		(property "Value" "200KR2F-L-GP"
			(at 0.064008 -3.993896 180)
			(unlocked yes)
			(layer "F.Fab")
			(hide yes)
			(effects
				(font
					(size 1.016 1.016)
					(thickness 0.1524)
				)
			)
		)
		(property "Device Type" "R402H16"
			(at 0.064008 -5.517896 180)
			(unlocked yes)
			(layer "F.Fab")
			(hide yes)
			(effects
				(font
					(size 1.016 1.016)
					(thickness 0.1524)
				)
			)
		)
		(duplicate_pad_numbers_are_jumpers no)
		(fp_line
			(start 0.508 -0.9398)
			(end -0.508 -0.9398)
			(stroke
				(width 0.1524)
				(type default)
			)
			(layer "F.SilkS")
		)
		(fp_line
			(start -0.508 -0.9398)
			(end -0.508 0.9398)
			(stroke
				(width 0.1524)
				(type default)
			)
			(layer "F.SilkS")
		)
		(fp_rect
			(start -0.508 0.9398)
			(end 0.508 -0.9398)
			(stroke
				(width 0)
				(type default)
			)
			(fill no)
			(layer "F.CrtYd")
		)
		(fp_rect
			(start -0.508 0.9398)
			(end 0.508 -0.9398)
			(stroke
				(width 0)
				(type default)
			)
			(fill no)
			(layer "F.Fab")
		)
		(pad "1" smd custom
			(at 0 -0.4445 180)
			(size 0.1397 0.1397)
			(layers "F.Cu" "F.Mask" "F.Paste")
			(net "SW_HDD_R12")
			(options
				(clearance outline)
				(anchor circle)
			)
			(primitives
				(gr_poly
					(pts
						(arc
							(start -0.1778 -0.2794)
							(mid -0.249642 -0.249642)
							(end -0.2794 -0.1778)
						)
						(arc
							(start -0.2794 0.1778)
							(mid -0.249642 0.249642)
							(end -0.1778 0.2794)
						)
						(arc
							(start 0.1778 0.2794)
							(mid 0.249642 0.249642)
							(end 0.2794 0.1778)
						)
						(arc
							(start 0.2794 -0.1778)
							(mid 0.249642 -0.249642)
							(end 0.1778 -0.2794)
						)
					)
					(width 0)
					(fill yes)
				)
			)
		)
		(pad "2" smd custom
			(at 0 0.4445 180)
			(size 0.1397 0.1397)
			(layers "F.Cu" "F.Mask" "F.Paste")
			(net "SW_HDD_N12")
			(options
				(clearance outline)
				(anchor circle)
			)
			(primitives
				(gr_poly
					(pts
						(arc
							(start -0.1778 -0.2794)
							(mid -0.249642 -0.249642)
							(end -0.2794 -0.1778)
						)
						(arc
							(start -0.2794 0.1778)
							(mid -0.249642 0.249642)
							(end -0.1778 0.2794)
						)
						(arc
							(start 0.1778 0.2794)
							(mid 0.249642 0.249642)
							(end 0.2794 0.1778)
						)
						(arc
							(start 0.2794 -0.1778)
							(mid 0.249642 -0.249642)
							(end 0.1778 -0.2794)
						)
					)
					(width 0)
					(fill yes)
				)
			)
		)
	)
	(footprint ""
		(layer "F.Cu")
		(at 433.359052 -171.809918 -90)
		(property "Reference" "R628"
			(at 0 0 270)
			(layer "F.SilkS")
			(hide yes)
			(effects
				(font
					(size 1.27 1.27)
				)
			)
		)
		(property "Value" "300KR2F-GP"
			(at 0.064008 -3.993896 270)
			(unlocked yes)
			(layer "F.Fab")
			(hide yes)
			(effects
				(font
					(size 1.016 1.016)
					(thickness 0.1524)
				)
			)
		)
		(property "Device Type" "R402H16"
			(at 0.064008 -5.517896 270)
			(unlocked yes)
			(layer "F.Fab")
			(hide yes)
			(effects
				(font
					(size 1.016 1.016)
					(thickness 0.1524)
				)
			)
		)
		(duplicate_pad_numbers_are_jumpers no)
		(fp_line
			(start -0.508 -0.9398)
			(end -0.508 0.9398)
			(stroke
				(width 0.1524)
				(type default)
			)
			(layer "F.SilkS")
		)
		(fp_line
			(start 0.508 -0.9398)
			(end -0.508 -0.9398)
			(stroke
				(width 0.1524)
				(type default)
			)
			(layer "F.SilkS")
		)
		(fp_rect
			(start -0.508 0.9398)
			(end 0.508 -0.9398)
			(stroke
				(width 0)
				(type default)
			)
			(fill no)
			(layer "F.CrtYd")
		)
		(fp_rect
			(start -0.508 0.9398)
			(end 0.508 -0.9398)
			(stroke
				(width 0)
				(type default)
			)
			(fill no)
			(layer "F.Fab")
		)
		(pad "1" smd custom
			(at 0 -0.4445 270)
			(size 0.1397 0.1397)
			(layers "F.Cu" "F.Mask" "F.Paste")
			(net "SW_HDD_N21")
			(options
				(clearance outline)
				(anchor circle)
			)
			(primitives
				(gr_poly
					(pts
						(arc
							(start -0.1778 -0.2794)
							(mid -0.249642 -0.249642)
							(end -0.2794 -0.1778)
						)
						(arc
							(start -0.2794 0.1778)
							(mid -0.249642 0.249642)
							(end -0.1778 0.2794)
						)
						(arc
							(start 0.1778 0.2794)
							(mid 0.249642 0.249642)
							(end 0.2794 0.1778)
						)
						(arc
							(start 0.2794 -0.1778)
							(mid 0.249642 -0.249642)
							(end 0.1778 -0.2794)
						)
					)
					(width 0)
					(fill yes)
				)
			)
		)
		(pad "2" smd custom
			(at 0 0.4445 270)
			(size 0.1397 0.1397)
			(layers "F.Cu" "F.Mask" "F.Paste")
			(net "P12V_A")
			(options
				(clearance outline)
				(anchor circle)
			)
			(primitives
				(gr_poly
					(pts
						(arc
							(start -0.1778 -0.2794)
							(mid -0.249642 -0.249642)
							(end -0.2794 -0.1778)
						)
						(arc
							(start -0.2794 0.1778)
							(mid -0.249642 0.249642)
							(end -0.1778 0.2794)
						)
						(arc
							(start 0.1778 0.2794)
							(mid 0.249642 0.249642)
							(end 0.2794 0.1778)
						)
						(arc
							(start 0.2794 -0.1778)
							(mid 0.249642 -0.249642)
							(end 0.1778 -0.2794)
						)
					)
					(width 0)
					(fill yes)
				)
			)
		)
	)
	(footprint ""
		(layer "F.Cu")
		(at 427.898052 -42.585894 180)
		(property "Reference" "R897"
			(at 0 0 180)
			(layer "F.SilkS")
			(hide yes)
			(effects
				(font
					(size 1.27 1.27)
				)
			)
		)
		(property "Value" "1KR2F-3-GP"
			(at 0.064008 -3.993896 180)
			(unlocked yes)
			(layer "F.Fab")
			(hide yes)
			(effects
				(font
					(size 1.016 1.016)
					(thickness 0.1524)
				)
			)
		)
		(property "Device Type" "R402H16"
			(at 0.064008 -5.517896 180)
			(unlocked yes)
			(layer "F.Fab")
			(hide yes)
			(effects
				(font
					(size 1.016 1.016)
					(thickness 0.1524)
				)
			)
		)
		(duplicate_pad_numbers_are_jumpers no)
		(fp_line
			(start 0.508 -0.9398)
			(end -0.508 -0.9398)
			(stroke
				(width 0.1524)
				(type default)
			)
			(layer "F.SilkS")
		)
		(fp_line
			(start -0.508 -0.9398)
			(end -0.508 0.9398)
			(stroke
				(width 0.1524)
				(type default)
			)
			(layer "F.SilkS")
		)
		(fp_rect
			(start -0.508 0.9398)
			(end 0.508 -0.9398)
			(stroke
				(width 0)
				(type default)
			)
			(fill no)
			(layer "F.CrtYd")
		)
		(fp_rect
			(start -0.508 0.9398)
			(end 0.508 -0.9398)
			(stroke
				(width 0)
				(type default)
			)
			(fill no)
			(layer "F.Fab")
		)
		(pad "1" smd custom
			(at 0 -0.4445 180)
			(size 0.1397 0.1397)
			(layers "F.Cu" "F.Mask" "F.Paste")
			(net "P3V3_STBY_A")
			(options
				(clearance outline)
				(anchor circle)
			)
			(primitives
				(gr_poly
					(pts
						(arc
							(start -0.1778 -0.2794)
							(mid -0.249642 -0.249642)
							(end -0.2794 -0.1778)
						)
						(arc
							(start -0.2794 0.1778)
							(mid -0.249642 0.249642)
							(end -0.1778 0.2794)
						)
						(arc
							(start 0.1778 0.2794)
							(mid 0.249642 0.249642)
							(end 0.2794 0.1778)
						)
						(arc
							(start 0.2794 -0.1778)
							(mid 0.249642 -0.249642)
							(end 0.1778 -0.2794)
						)
					)
					(width 0)
					(fill yes)
				)
			)
		)
		(pad "2" smd custom
			(at 0 0.4445 180)
			(size 0.1397 0.1397)
			(layers "F.Cu" "F.Mask" "F.Paste")
			(net "SW_PWR_R_HDD33")
			(options
				(clearance outline)
				(anchor circle)
			)
			(primitives
				(gr_poly
					(pts
						(arc
							(start -0.1778 -0.2794)
							(mid -0.249642 -0.249642)
							(end -0.2794 -0.1778)
						)
						(arc
							(start -0.2794 0.1778)
							(mid -0.249642 0.249642)
							(end -0.1778 0.2794)
						)
						(arc
							(start 0.1778 0.2794)
							(mid 0.249642 0.249642)
							(end 0.2794 0.1778)
						)
						(arc
							(start 0.2794 -0.1778)
							(mid 0.249642 -0.249642)
							(end 0.1778 -0.2794)
						)
					)
					(width 0)
					(fill yes)
				)
			)
		)
	)
	(footprint ""
		(layer "F.Cu")
		(at 366.6998 -132.7404)
		(property "Reference" "C563"
			(at 0 0 0)
			(layer "F.SilkS")
			(hide yes)
			(effects
				(font
					(size 1.27 1.27)
				)
			)
		)
		(property "Value" "SC1U16V3KX-5GP"
			(at 0 -2.8194 0)
			(unlocked yes)
			(layer "F.Fab")
			(hide yes)
			(effects
				(font
					(size 1.016 1.016)
					(thickness 0.1524)
				)
			)
		)
		(property "Device Type" "C603H36"
			(at 0 -4.3434 0)
			(unlocked yes)
			(layer "F.Fab")
			(hide yes)
			(effects
				(font
					(size 1.016 1.016)
					(thickness 0.1524)
				)
			)
		)
		(duplicate_pad_numbers_are_jumpers no)
		(fp_line
			(start 0.508 0)
			(end -0.508 0)
			(stroke
				(width 0.2032)
				(type default)
			)
			(layer "F.SilkS")
		)
		(fp_rect
			(start -0.5842 1.3335)
			(end 0.5842 -1.3335)
			(stroke
				(width 0)
				(type default)
			)
			(fill no)
			(layer "F.CrtYd")
		)
		(fp_rect
			(start -0.5842 1.3335)
			(end 0.5842 -1.3335)
			(stroke
				(width 0)
				(type default)
			)
			(fill no)
			(layer "F.Fab")
		)
		(pad "1" smd custom
			(at 0 -0.762)
			(size 0.2159 0.2159)
			(layers "F.Cu" "F.Mask" "F.Paste")
			(net "MB1_VCAP_R")
			(options
				(clearance outline)
				(anchor circle)
			)
			(primitives
				(gr_poly
					(pts
						(arc
							(start -0.3302 -0.4318)
							(mid -0.402042 -0.402042)
							(end -0.4318 -0.3302)
						)
						(arc
							(start -0.4318 0.3302)
							(mid -0.402042 0.402042)
							(end -0.3302 0.4318)
						)
						(arc
							(start 0.3302 0.4318)
							(mid 0.402042 0.402042)
							(end 0.4318 0.3302)
						)
						(arc
							(start 0.4318 -0.3302)
							(mid 0.402042 -0.402042)
							(end 0.3302 -0.4318)
						)
					)
					(width 0)
					(fill yes)
				)
			)
		)
		(pad "2" smd custom
			(at 0 0.762)
			(size 0.2159 0.2159)
			(layers "F.Cu" "F.Mask" "F.Paste")
			(net "AGND_CURRENT_MONOB")
			(options
				(clearance outline)
				(anchor circle)
			)
			(primitives
				(gr_poly
					(pts
						(arc
							(start -0.3302 -0.4318)
							(mid -0.402042 -0.402042)
							(end -0.4318 -0.3302)
						)
						(arc
							(start -0.4318 0.3302)
							(mid -0.402042 0.402042)
							(end -0.3302 0.4318)
						)
						(arc
							(start 0.3302 0.4318)
							(mid 0.402042 0.402042)
							(end 0.4318 0.3302)
						)
						(arc
							(start 0.4318 -0.3302)
							(mid 0.402042 -0.402042)
							(end 0.3302 -0.4318)
						)
					)
					(width 0)
					(fill yes)
				)
			)
		)
	)
	(footprint ""
		(layer "F.Cu")
		(at 431.581052 -275.735542 180)
		(property "Reference" "R351"
			(at 0 0 180)
			(layer "F.SilkS")
			(hide yes)
			(effects
				(font
					(size 1.27 1.27)
				)
			)
		)
		(property "Value" "4K7R2J-2-GP"
			(at 0.064008 -3.993896 180)
			(unlocked yes)
			(layer "F.Fab")
			(hide yes)
			(effects
				(font
					(size 1.016 1.016)
					(thickness 0.1524)
				)
			)
		)
		(property "Device Type" "R402H16"
			(at 0.064008 -5.517896 180)
			(unlocked yes)
			(layer "F.Fab")
			(hide yes)
			(effects
				(font
					(size 1.016 1.016)
					(thickness 0.1524)
				)
			)
		)
		(duplicate_pad_numbers_are_jumpers no)
		(fp_line
			(start 0.508 -0.9398)
			(end -0.508 -0.9398)
			(stroke
				(width 0.1524)
				(type default)
			)
			(layer "F.SilkS")
		)
		(fp_line
			(start -0.508 -0.9398)
			(end -0.508 0.9398)
			(stroke
				(width 0.1524)
				(type default)
			)
			(layer "F.SilkS")
		)
		(fp_rect
			(start -0.508 0.9398)
			(end 0.508 -0.9398)
			(stroke
				(width 0)
				(type default)
			)
			(fill no)
			(layer "F.CrtYd")
		)
		(fp_rect
			(start -0.508 0.9398)
			(end 0.508 -0.9398)
			(stroke
				(width 0)
				(type default)
			)
			(fill no)
			(layer "F.Fab")
		)
		(pad "1" smd custom
			(at 0 -0.4445 180)
			(size 0.1397 0.1397)
			(layers "F.Cu" "F.Mask" "F.Paste")
			(net "P12V_A")
			(options
				(clearance outline)
				(anchor circle)
			)
			(primitives
				(gr_poly
					(pts
						(arc
							(start -0.1778 -0.2794)
							(mid -0.249642 -0.249642)
							(end -0.2794 -0.1778)
						)
						(arc
							(start -0.2794 0.1778)
							(mid -0.249642 0.249642)
							(end -0.1778 0.2794)
						)
						(arc
							(start 0.1778 0.2794)
							(mid 0.249642 0.249642)
							(end 0.2794 0.1778)
						)
						(arc
							(start 0.2794 -0.1778)
							(mid 0.249642 -0.249642)
							(end 0.1778 -0.2794)
						)
					)
					(width 0)
					(fill yes)
				)
			)
		)
		(pad "2" smd custom
			(at 0 0.4445 180)
			(size 0.1397 0.1397)
			(layers "F.Cu" "F.Mask" "F.Paste")
			(net "SW_HDD_R9")
			(options
				(clearance outline)
				(anchor circle)
			)
			(primitives
				(gr_poly
					(pts
						(arc
							(start -0.1778 -0.2794)
							(mid -0.249642 -0.249642)
							(end -0.2794 -0.1778)
						)
						(arc
							(start -0.2794 0.1778)
							(mid -0.249642 0.249642)
							(end -0.1778 0.2794)
						)
						(arc
							(start 0.1778 0.2794)
							(mid 0.249642 0.249642)
							(end 0.2794 0.1778)
						)
						(arc
							(start 0.2794 -0.1778)
							(mid 0.249642 -0.249642)
							(end 0.1778 -0.2794)
						)
					)
					(width 0)
					(fill yes)
				)
			)
		)
	)
	(footprint ""
		(layer "F.Cu")
		(at 82.006948 -294.683942 90)
		(property "Reference" "R179"
			(at 0 0 90)
			(layer "F.SilkS")
			(hide yes)
			(effects
				(font
					(size 1.27 1.27)
				)
			)
		)
		(property "Value" "2R6F-GP"
			(at -0.0508 -4.8514 90)
			(unlocked yes)
			(layer "F.Fab")
			(hide yes)
			(effects
				(font
					(size 1.016 1.016)
					(thickness 0.1524)
				)
			)
		)
		(property "Device Type" "R1206H26"
			(at 0 -6.3754 90)
			(unlocked yes)
			(layer "F.Fab")
			(hide yes)
			(effects
				(font
					(size 1.016 1.016)
					(thickness 0.1524)
				)
			)
		)
		(duplicate_pad_numbers_are_jumpers no)
		(fp_line
			(start 1.016 -2.2352)
			(end 1.016 2.2352)
			(stroke
				(width 0.1524)
				(type default)
			)
			(layer "F.SilkS")
		)
		(fp_line
			(start -1.016 -2.2352)
			(end 1.016 -2.2352)
			(stroke
				(width 0.1524)
				(type default)
			)
			(layer "F.SilkS")
		)
		(fp_line
			(start 1.016 2.2352)
			(end -1.016 2.2352)
			(stroke
				(width 0.1524)
				(type default)
			)
			(layer "F.SilkS")
		)
		(fp_line
			(start -1.016 2.2352)
			(end -1.016 -2.2352)
			(stroke
				(width 0.1524)
				(type default)
			)
			(layer "F.SilkS")
		)
		(fp_rect
			(start -1.0922 2.3114)
			(end 1.0922 -2.3114)
			(stroke
				(width 0)
				(type default)
			)
			(fill no)
			(layer "F.CrtYd")
		)
		(fp_poly
			(pts
				(xy -1.0922 -2.3114) (xy 1.0922 -2.3114) (xy 1.0922 2.3114) (xy -1.0922 2.3114)
			)
			(stroke
				(width 0)
				(type default)
			)
			(fill no)
			(layer "F.Fab")
		)
		(pad "1" smd rect
			(at 0 -1.397 90)
			(size 1.651 1.27)
			(layers "F.Cu" "F.Mask" "F.Paste")
			(net "P12V_HDD2")
		)
		(pad "2" smd rect
			(at 0 1.397 90)
			(size 1.651 1.27)
			(layers "F.Cu" "F.Mask" "F.Paste")
			(net "12V_PRE_2")
		)
	)
)
